(kicad_pcb
	(version 20260206)
	(generator "pcbnew")
	(generator_version "10.0")
	(general
		(thickness 1.6)
		(legacy_teardrops no)
	)
	(paper "A4")
	(title_block
		(title "04192023_DAF0TMB3IC0_F0TG_MB_C_brd_V02_OCP.brd")
		(comment 1 "Grand Teton / footprints 2220-2225 of 8354")
	)
	(layers
		(0 "F.Cu" signal "TOP")
		(4 "In1.Cu" signal "GND")
		(6 "In2.Cu" signal "IN1")
		(8 "In3.Cu" signal "GND1")
		(10 "In4.Cu" signal "IN2")
		(12 "In5.Cu" signal "GND2")
		(14 "In6.Cu" signal "IN3")
		(16 "In7.Cu" signal "GND3")
		(18 "In8.Cu" signal "VCC")
		(20 "In9.Cu" signal "VCC1")
		(22 "In10.Cu" signal "GND4")
		(24 "In11.Cu" signal "IN4")
		(26 "In12.Cu" signal "GND5")
		(28 "In13.Cu" signal "IN5")
		(30 "In14.Cu" signal "GND6")
		(32 "In15.Cu" signal "IN6")
		(34 "In16.Cu" signal "GND7")
		(2 "B.Cu" signal "BOTTOM")
		(9 "F.Adhes" user "F.Adhesive")
		(11 "B.Adhes" user "B.Adhesive")
		(13 "F.Paste" user "Package Geometry/Pastemask Top")
		(15 "B.Paste" user "Package Geometry/Pastemask Bottom")
		(5 "F.SilkS" user "Ref Des/Silkscreen Top")
		(7 "B.SilkS" user "Ref Des/Silkscreen Bottom")
		(1 "F.Mask" user "Board Geometry/Soldermask Top")
		(3 "B.Mask" user "Board Geometry/Soldermask Bottom")
		(17 "Dwgs.User" user "User.Drawings")
		(19 "Cmts.User" user "User.Comments")
		(21 "Eco1.User" user "User.Eco1")
		(23 "Eco2.User" user "User.Eco2")
		(25 "Edge.Cuts" user "Board Geometry/Outline")
		(27 "Margin" user)
		(31 "F.CrtYd" user "Package Geometry/Place Bound Top")
		(29 "B.CrtYd" user "Package Geometry/Place Bound Bottom")
		(35 "F.Fab" user "Ref Des/Assembly Top")
		(33 "B.Fab" user "Ref Des/Assembly Bottom")
	)
	(footprint ""
		(layer "F.Cu")
		(at 418.11194 -105.207308 180)
		(property "Reference" "PC2159"
			(at 0 0 180)
			(layer "F.SilkS")
			(hide yes)
			(effects
				(font
					(size 1.27 1.27)
				)
			)
		)
		(property "Value" ""
			(at 0 0 180)
			(layer "F.Fab")
			(effects
				(font
					(size 1.27 1.27)
				)
			)
		)
		(duplicate_pad_numbers_are_jumpers no)
		(fp_line
			(start 0.7874 0.4064)
			(end -0.7874 0.4064)
			(stroke
				(width 0.1524)
				(type default)
			)
			(layer "F.SilkS")
		)
		(fp_line
			(start 0.7874 -0.4064)
			(end 0.7874 0.4064)
			(stroke
				(width 0.1524)
				(type default)
			)
			(layer "F.SilkS")
		)
		(fp_line
			(start -0.7874 0.4064)
			(end -0.7874 -0.4064)
			(stroke
				(width 0.1524)
				(type default)
			)
			(layer "F.SilkS")
		)
		(fp_line
			(start -0.7874 -0.4064)
			(end 0.7874 -0.4064)
			(stroke
				(width 0.1524)
				(type default)
			)
			(layer "F.SilkS")
		)
		(fp_line
			(start 0.67945 0.3048)
			(end 0.120396 0.3048)
			(stroke
				(width 0.1)
				(type default)
			)
			(layer "F.Fab")
		)
		(fp_line
			(start 0.67945 -0.3048)
			(end 0.67945 0.3048)
			(stroke
				(width 0.1)
				(type default)
			)
			(layer "F.Fab")
		)
		(fp_line
			(start 0.12065 -0.2794)
			(end 0.12065 -0.3048)
			(stroke
				(width 0.1)
				(type default)
			)
			(layer "F.Fab")
		)
		(fp_line
			(start 0.12065 -0.3048)
			(end 0.67945 -0.3048)
			(stroke
				(width 0.1)
				(type default)
			)
			(layer "F.Fab")
		)
		(fp_line
			(start 0.120396 0.3048)
			(end 0.120396 0.2794)
			(stroke
				(width 0.1)
				(type default)
			)
			(layer "F.Fab")
		)
		(fp_line
			(start 0.120396 0.2794)
			(end -0.12065 0.2794)
			(stroke
				(width 0.1)
				(type default)
			)
			(layer "F.Fab")
		)
		(fp_line
			(start -0.12065 0.3048)
			(end -0.67945 0.3048)
			(stroke
				(width 0.1)
				(type default)
			)
			(layer "F.Fab")
		)
		(fp_line
			(start -0.12065 0.2794)
			(end -0.12065 0.3048)
			(stroke
				(width 0.1)
				(type default)
			)
			(layer "F.Fab")
		)
		(fp_line
			(start -0.12065 -0.2794)
			(end 0.12065 -0.2794)
			(stroke
				(width 0.1)
				(type default)
			)
			(layer "F.Fab")
		)
		(fp_line
			(start -0.12065 -0.305054)
			(end -0.12065 -0.2794)
			(stroke
				(width 0.1)
				(type default)
			)
			(layer "F.Fab")
		)
		(fp_line
			(start -0.67945 0.3048)
			(end -0.67945 -0.305054)
			(stroke
				(width 0.1)
				(type default)
			)
			(layer "F.Fab")
		)
		(fp_line
			(start -0.67945 -0.305054)
			(end -0.12065 -0.305054)
			(stroke
				(width 0.1)
				(type default)
			)
			(layer "F.Fab")
		)
		(pad "1" smd circle
			(at -0.40005 0 180)
			(size 0 0)
			(layers "F.Cu" "F.Mask" "F.Paste")
			(net "P3V3_AUX")
		)
		(pad "2" smd circle
			(at 0.40005 0 180)
			(size 0 0)
			(layers "F.Cu" "F.Mask" "F.Paste")
			(net "GND")
		)
	)
	(footprint ""
		(layer "F.Cu")
		(at 357.284782 -413.046418 180)
		(property "Reference" "R4156"
			(at 0 0 180)
			(layer "F.SilkS")
			(hide yes)
			(effects
				(font
					(size 1.27 1.27)
				)
			)
		)
		(property "Value" ""
			(at 0 0 180)
			(layer "F.Fab")
			(effects
				(font
					(size 1.27 1.27)
				)
			)
		)
		(duplicate_pad_numbers_are_jumpers no)
		(fp_line
			(start 0.7874 0.4064)
			(end -0.7874 0.4064)
			(stroke
				(width 0.1524)
				(type default)
			)
			(layer "F.SilkS")
		)
		(fp_line
			(start 0.7874 -0.4064)
			(end 0.7874 0.4064)
			(stroke
				(width 0.1524)
				(type default)
			)
			(layer "F.SilkS")
		)
		(fp_line
			(start -0.7874 0.4064)
			(end -0.7874 -0.4064)
			(stroke
				(width 0.1524)
				(type default)
			)
			(layer "F.SilkS")
		)
		(fp_line
			(start -0.7874 -0.4064)
			(end 0.7874 -0.4064)
			(stroke
				(width 0.1524)
				(type default)
			)
			(layer "F.SilkS")
		)
		(fp_line
			(start 0.67945 0.3048)
			(end 0.120396 0.3048)
			(stroke
				(width 0.1)
				(type default)
			)
			(layer "F.Fab")
		)
		(fp_line
			(start 0.67945 -0.3048)
			(end 0.67945 0.3048)
			(stroke
				(width 0.1)
				(type default)
			)
			(layer "F.Fab")
		)
		(fp_line
			(start 0.12065 -0.2794)
			(end 0.12065 -0.3048)
			(stroke
				(width 0.1)
				(type default)
			)
			(layer "F.Fab")
		)
		(fp_line
			(start 0.12065 -0.3048)
			(end 0.67945 -0.3048)
			(stroke
				(width 0.1)
				(type default)
			)
			(layer "F.Fab")
		)
		(fp_line
			(start 0.120396 0.3048)
			(end 0.120396 0.2794)
			(stroke
				(width 0.1)
				(type default)
			)
			(layer "F.Fab")
		)
		(fp_line
			(start 0.120396 0.2794)
			(end -0.12065 0.2794)
			(stroke
				(width 0.1)
				(type default)
			)
			(layer "F.Fab")
		)
		(fp_line
			(start -0.12065 0.3048)
			(end -0.67945 0.3048)
			(stroke
				(width 0.1)
				(type default)
			)
			(layer "F.Fab")
		)
		(fp_line
			(start -0.12065 0.2794)
			(end -0.12065 0.3048)
			(stroke
				(width 0.1)
				(type default)
			)
			(layer "F.Fab")
		)
		(fp_line
			(start -0.12065 -0.2794)
			(end 0.12065 -0.2794)
			(stroke
				(width 0.1)
				(type default)
			)
			(layer "F.Fab")
		)
		(fp_line
			(start -0.12065 -0.305054)
			(end -0.12065 -0.2794)
			(stroke
				(width 0.1)
				(type default)
			)
			(layer "F.Fab")
		)
		(fp_line
			(start -0.67945 0.3048)
			(end -0.67945 -0.305054)
			(stroke
				(width 0.1)
				(type default)
			)
			(layer "F.Fab")
		)
		(fp_line
			(start -0.67945 -0.305054)
			(end -0.12065 -0.305054)
			(stroke
				(width 0.1)
				(type default)
			)
			(layer "F.Fab")
		)
		(pad "1" smd circle
			(at -0.40005 0 180)
			(size 0 0)
			(layers "F.Cu" "F.Mask" "F.Paste")
			(net "P3V3_AUX")
		)
		(pad "2" smd circle
			(at 0.40005 0 180)
			(size 0 0)
			(layers "F.Cu" "F.Mask" "F.Paste")
			(net "PRSNT_CABLE_GPU_A1_ISO_N")
		)
	)
	(footprint ""
		(layer "F.Cu")
		(at 179.24272 -349.56115 90)
		(property "Reference" "PR520"
			(at 0 0 90)
			(layer "F.SilkS")
			(hide yes)
			(effects
				(font
					(size 1.27 1.27)
				)
			)
		)
		(property "Value" ""
			(at 0 0 90)
			(layer "F.Fab")
			(effects
				(font
					(size 1.27 1.27)
				)
			)
		)
		(duplicate_pad_numbers_are_jumpers no)
		(fp_line
			(start 0.7874 -0.4064)
			(end 0.7874 0.4064)
			(stroke
				(width 0.1524)
				(type default)
			)
			(layer "F.SilkS")
		)
		(fp_line
			(start -0.7874 -0.4064)
			(end 0.7874 -0.4064)
			(stroke
				(width 0.1524)
				(type default)
			)
			(layer "F.SilkS")
		)
		(fp_line
			(start 0.7874 0.4064)
			(end -0.7874 0.4064)
			(stroke
				(width 0.1524)
				(type default)
			)
			(layer "F.SilkS")
		)
		(fp_line
			(start -0.7874 0.4064)
			(end -0.7874 -0.4064)
			(stroke
				(width 0.1524)
				(type default)
			)
			(layer "F.SilkS")
		)
		(fp_line
			(start -0.12065 -0.305054)
			(end -0.12065 -0.2794)
			(stroke
				(width 0.1)
				(type default)
			)
			(layer "F.Fab")
		)
		(fp_line
			(start -0.67945 -0.305054)
			(end -0.12065 -0.305054)
			(stroke
				(width 0.1)
				(type default)
			)
			(layer "F.Fab")
		)
		(fp_line
			(start 0.67945 -0.3048)
			(end 0.67945 0.3048)
			(stroke
				(width 0.1)
				(type default)
			)
			(layer "F.Fab")
		)
		(fp_line
			(start 0.12065 -0.3048)
			(end 0.67945 -0.3048)
			(stroke
				(width 0.1)
				(type default)
			)
			(layer "F.Fab")
		)
		(fp_line
			(start 0.12065 -0.2794)
			(end 0.12065 -0.3048)
			(stroke
				(width 0.1)
				(type default)
			)
			(layer "F.Fab")
		)
		(fp_line
			(start -0.12065 -0.2794)
			(end 0.12065 -0.2794)
			(stroke
				(width 0.1)
				(type default)
			)
			(layer "F.Fab")
		)
		(fp_line
			(start 0.120396 0.2794)
			(end -0.12065 0.2794)
			(stroke
				(width 0.1)
				(type default)
			)
			(layer "F.Fab")
		)
		(fp_line
			(start -0.12065 0.2794)
			(end -0.12065 0.3048)
			(stroke
				(width 0.1)
				(type default)
			)
			(layer "F.Fab")
		)
		(fp_line
			(start 0.67945 0.3048)
			(end 0.120396 0.3048)
			(stroke
				(width 0.1)
				(type default)
			)
			(layer "F.Fab")
		)
		(fp_line
			(start 0.120396 0.3048)
			(end 0.120396 0.2794)
			(stroke
				(width 0.1)
				(type default)
			)
			(layer "F.Fab")
		)
		(fp_line
			(start -0.12065 0.3048)
			(end -0.67945 0.3048)
			(stroke
				(width 0.1)
				(type default)
			)
			(layer "F.Fab")
		)
		(fp_line
			(start -0.67945 0.3048)
			(end -0.67945 -0.305054)
			(stroke
				(width 0.1)
				(type default)
			)
			(layer "F.Fab")
		)
		(pad "1" smd circle
			(at -0.40005 0 90)
			(size 0 0)
			(layers "F.Cu" "F.Mask" "F.Paste")
			(net "SW_PVDD11_S3_P1_SW1_RC")
		)
		(pad "2" smd circle
			(at 0.40005 0 90)
			(size 0 0)
			(layers "F.Cu" "F.Mask" "F.Paste")
			(net "GND")
		)
	)
	(footprint ""
		(layer "F.Cu")
		(at 80.223106 -57.874154 180)
		(property "Reference" "R3571"
			(at 0 0 180)
			(layer "F.SilkS")
			(hide yes)
			(effects
				(font
					(size 1.27 1.27)
				)
			)
		)
		(property "Value" ""
			(at 0 0 180)
			(layer "F.Fab")
			(effects
				(font
					(size 1.27 1.27)
				)
			)
		)
		(duplicate_pad_numbers_are_jumpers no)
		(fp_line
			(start 0.7874 0.4064)
			(end -0.7874 0.4064)
			(stroke
				(width 0.1524)
				(type default)
			)
			(layer "F.SilkS")
		)
		(fp_line
			(start 0.7874 -0.4064)
			(end 0.7874 0.4064)
			(stroke
				(width 0.1524)
				(type default)
			)
			(layer "F.SilkS")
		)
		(fp_line
			(start -0.7874 0.4064)
			(end -0.7874 -0.4064)
			(stroke
				(width 0.1524)
				(type default)
			)
			(layer "F.SilkS")
		)
		(fp_line
			(start -0.7874 -0.4064)
			(end 0.7874 -0.4064)
			(stroke
				(width 0.1524)
				(type default)
			)
			(layer "F.SilkS")
		)
		(fp_line
			(start 0.67945 0.3048)
			(end 0.120396 0.3048)
			(stroke
				(width 0.1)
				(type default)
			)
			(layer "F.Fab")
		)
		(fp_line
			(start 0.67945 -0.3048)
			(end 0.67945 0.3048)
			(stroke
				(width 0.1)
				(type default)
			)
			(layer "F.Fab")
		)
		(fp_line
			(start 0.12065 -0.2794)
			(end 0.12065 -0.3048)
			(stroke
				(width 0.1)
				(type default)
			)
			(layer "F.Fab")
		)
		(fp_line
			(start 0.12065 -0.3048)
			(end 0.67945 -0.3048)
			(stroke
				(width 0.1)
				(type default)
			)
			(layer "F.Fab")
		)
		(fp_line
			(start 0.120396 0.3048)
			(end 0.120396 0.2794)
			(stroke
				(width 0.1)
				(type default)
			)
			(layer "F.Fab")
		)
		(fp_line
			(start 0.120396 0.2794)
			(end -0.12065 0.2794)
			(stroke
				(width 0.1)
				(type default)
			)
			(layer "F.Fab")
		)
		(fp_line
			(start -0.12065 0.3048)
			(end -0.67945 0.3048)
			(stroke
				(width 0.1)
				(type default)
			)
			(layer "F.Fab")
		)
		(fp_line
			(start -0.12065 0.2794)
			(end -0.12065 0.3048)
			(stroke
				(width 0.1)
				(type default)
			)
			(layer "F.Fab")
		)
		(fp_line
			(start -0.12065 -0.2794)
			(end 0.12065 -0.2794)
			(stroke
				(width 0.1)
				(type default)
			)
			(layer "F.Fab")
		)
		(fp_line
			(start -0.12065 -0.305054)
			(end -0.12065 -0.2794)
			(stroke
				(width 0.1)
				(type default)
			)
			(layer "F.Fab")
		)
		(fp_line
			(start -0.67945 0.3048)
			(end -0.67945 -0.305054)
			(stroke
				(width 0.1)
				(type default)
			)
			(layer "F.Fab")
		)
		(fp_line
			(start -0.67945 -0.305054)
			(end -0.12065 -0.305054)
			(stroke
				(width 0.1)
				(type default)
			)
			(layer "F.Fab")
		)
		(pad "1" smd circle
			(at -0.40005 0 180)
			(size 0 0)
			(layers "F.Cu" "F.Mask" "F.Paste")
			(net "P3V3_OCP_V3_2")
		)
		(pad "2" smd circle
			(at 0.40005 0 180)
			(size 0 0)
			(layers "F.Cu" "F.Mask" "F.Paste")
			(net "VSENSE_P12V_INA230_3_INN")
		)
	)
	(footprint ""
		(layer "F.Cu")
		(at 400.407378 -327.395332 180)
		(property "Reference" "R466"
			(at 0 0 180)
			(layer "F.SilkS")
			(hide yes)
			(effects
				(font
					(size 1.27 1.27)
				)
			)
		)
		(property "Value" ""
			(at 0 0 180)
			(layer "F.Fab")
			(effects
				(font
					(size 1.27 1.27)
				)
			)
		)
		(duplicate_pad_numbers_are_jumpers no)
		(fp_line
			(start 0.7874 0.4064)
			(end -0.7874 0.4064)
			(stroke
				(width 0.1524)
				(type default)
			)
			(layer "F.SilkS")
		)
		(fp_line
			(start 0.7874 -0.4064)
			(end 0.7874 0.4064)
			(stroke
				(width 0.1524)
				(type default)
			)
			(layer "F.SilkS")
		)
		(fp_line
			(start -0.7874 0.4064)
			(end -0.7874 -0.4064)
			(stroke
				(width 0.1524)
				(type default)
			)
			(layer "F.SilkS")
		)
		(fp_line
			(start -0.7874 -0.4064)
			(end 0.7874 -0.4064)
			(stroke
				(width 0.1524)
				(type default)
			)
			(layer "F.SilkS")
		)
		(fp_line
			(start 0.67945 0.3048)
			(end 0.120396 0.3048)
			(stroke
				(width 0.1)
				(type default)
			)
			(layer "F.Fab")
		)
		(fp_line
			(start 0.67945 -0.3048)
			(end 0.67945 0.3048)
			(stroke
				(width 0.1)
				(type default)
			)
			(layer "F.Fab")
		)
		(fp_line
			(start 0.12065 -0.2794)
			(end 0.12065 -0.3048)
			(stroke
				(width 0.1)
				(type default)
			)
			(layer "F.Fab")
		)
		(fp_line
			(start 0.12065 -0.3048)
			(end 0.67945 -0.3048)
			(stroke
				(width 0.1)
				(type default)
			)
			(layer "F.Fab")
		)
		(fp_line
			(start 0.120396 0.3048)
			(end 0.120396 0.2794)
			(stroke
				(width 0.1)
				(type default)
			)
			(layer "F.Fab")
		)
		(fp_line
			(start 0.120396 0.2794)
			(end -0.12065 0.2794)
			(stroke
				(width 0.1)
				(type default)
			)
			(layer "F.Fab")
		)
		(fp_line
			(start -0.12065 0.3048)
			(end -0.67945 0.3048)
			(stroke
				(width 0.1)
				(type default)
			)
			(layer "F.Fab")
		)
		(fp_line
			(start -0.12065 0.2794)
			(end -0.12065 0.3048)
			(stroke
				(width 0.1)
				(type default)
			)
			(layer "F.Fab")
		)
		(fp_line
			(start -0.12065 -0.2794)
			(end 0.12065 -0.2794)
			(stroke
				(width 0.1)
				(type default)
			)
			(layer "F.Fab")
		)
		(fp_line
			(start -0.12065 -0.305054)
			(end -0.12065 -0.2794)
			(stroke
				(width 0.1)
				(type default)
			)
			(layer "F.Fab")
		)
		(fp_line
			(start -0.67945 0.3048)
			(end -0.67945 -0.305054)
			(stroke
				(width 0.1)
				(type default)
			)
			(layer "F.Fab")
		)
		(fp_line
			(start -0.67945 -0.305054)
			(end -0.12065 -0.305054)
			(stroke
				(width 0.1)
				(type default)
			)
			(layer "F.Fab")
		)
		(pad "1" smd circle
			(at -0.40005 0 180)
			(size 0 0)
			(layers "F.Cu" "F.Mask" "F.Paste")
			(net "SPI_CPU0_D2")
		)
		(pad "2" smd circle
			(at 0.40005 0 180)
			(size 0 0)
			(layers "F.Cu" "F.Mask" "F.Paste")
			(net "SPI_CPU0_R_D2")
		)
	)
	(footprint ""
		(layer "F.Cu")
		(at 182.664608 -413.786574 -90)
		(property "Reference" "R2921"
			(at 0 0 270)
			(layer "F.SilkS")
			(hide yes)
			(effects
				(font
					(size 1.27 1.27)
				)
			)
		)
		(property "Value" ""
			(at 0 0 270)
			(layer "F.Fab")
			(effects
				(font
					(size 1.27 1.27)
				)
			)
		)
		(duplicate_pad_numbers_are_jumpers no)
		(fp_line
			(start -0.7874 0.4064)
			(end -0.7874 -0.4064)
			(stroke
				(width 0.1524)
				(type default)
			)
			(layer "F.SilkS")
		)
		(fp_line
			(start 0.7874 0.4064)
			(end -0.7874 0.4064)
			(stroke
				(width 0.1524)
				(type default)
			)
			(layer "F.SilkS")
		)
		(fp_line
			(start -0.7874 -0.4064)
			(end 0.7874 -0.4064)
			(stroke
				(width 0.1524)
				(type default)
			)
			(layer "F.SilkS")
		)
		(fp_line
			(start 0.7874 -0.4064)
			(end 0.7874 0.4064)
			(stroke
				(width 0.1524)
				(type default)
			)
			(layer "F.SilkS")
		)
		(fp_line
			(start -0.67945 0.3048)
			(end -0.67945 -0.305054)
			(stroke
				(width 0.1)
				(type default)
			)
			(layer "F.Fab")
		)
		(fp_line
			(start -0.12065 0.3048)
			(end -0.67945 0.3048)
			(stroke
				(width 0.1)
				(type default)
			)
			(layer "F.Fab")
		)
		(fp_line
			(start 0.120396 0.3048)
			(end 0.120396 0.2794)
			(stroke
				(width 0.1)
				(type default)
			)
			(layer "F.Fab")
		)
		(fp_line
			(start 0.67945 0.3048)
			(end 0.120396 0.3048)
			(stroke
				(width 0.1)
				(type default)
			)
			(layer "F.Fab")
		)
		(fp_line
			(start -0.12065 0.2794)
			(end -0.12065 0.3048)
			(stroke
				(width 0.1)
				(type default)
			)
			(layer "F.Fab")
		)
		(fp_line
			(start 0.120396 0.2794)
			(end -0.12065 0.2794)
			(stroke
				(width 0.1)
				(type default)
			)
			(layer "F.Fab")
		)
		(fp_line
			(start -0.12065 -0.2794)
			(end 0.12065 -0.2794)
			(stroke
				(width 0.1)
				(type default)
			)
			(layer "F.Fab")
		)
		(fp_line
			(start 0.12065 -0.2794)
			(end 0.12065 -0.3048)
			(stroke
				(width 0.1)
				(type default)
			)
			(layer "F.Fab")
		)
		(fp_line
			(start 0.12065 -0.3048)
			(end 0.67945 -0.3048)
			(stroke
				(width 0.1)
				(type default)
			)
			(layer "F.Fab")
		)
		(fp_line
			(start 0.67945 -0.3048)
			(end 0.67945 0.3048)
			(stroke
				(width 0.1)
				(type default)
			)
			(layer "F.Fab")
		)
		(fp_line
			(start -0.67945 -0.305054)
			(end -0.12065 -0.305054)
			(stroke
				(width 0.1)
				(type default)
			)
			(layer "F.Fab")
		)
		(fp_line
			(start -0.12065 -0.305054)
			(end -0.12065 -0.2794)
			(stroke
				(width 0.1)
				(type default)
			)
			(layer "F.Fab")
		)
		(pad "1" smd circle
			(at -0.40005 0 270)
			(size 0 0)
			(layers "F.Cu" "F.Mask" "F.Paste")
			(net "P3V3_AUX")
		)
		(pad "2" smd circle
			(at 0.40005 0 270)
			(size 0 0)
			(layers "F.Cu" "F.Mask" "F.Paste")
			(net "RST_SMB_SWITCH_N")
		)
	)
)
